(kicad_pcb
	(version 20260206)
	(generator "pcbnew")
	(generator_version "10.0")
	(general
		(thickness 1.6)
		(legacy_teardrops no)
	)
	(paper "A4")
	(title_block
		(title "Bryce Canyon_R.DPB_16317-1_OCP.brd")
		(comment 1 "Bryce Canyon / footprints 1142-1148 of 2099")
	)
	(layers
		(0 "F.Cu" signal "TOP")
		(4 "In1.Cu" signal "L2GND")
		(6 "In2.Cu" signal "L3")
		(8 "In3.Cu" signal "L4VCC")
		(10 "In4.Cu" signal "L5VCC")
		(12 "In5.Cu" signal "L6")
		(14 "In6.Cu" signal "L7GND")
		(2 "B.Cu" signal "BOTTOM")
		(9 "F.Adhes" user "F.Adhesive")
		(11 "B.Adhes" user "B.Adhesive")
		(13 "F.Paste" user "Package Geometry/Pastemask Top")
		(15 "B.Paste" user "Package Geometry/Pastemask Bottom")
		(5 "F.SilkS" user "Ref Des/Silkscreen Top")
		(7 "B.SilkS" user "Ref Des/Silkscreen Bottom")
		(1 "F.Mask" user "Board Geometry/Soldermask Top")
		(3 "B.Mask" user "Board Geometry/Soldermask Bottom")
		(17 "Dwgs.User" user "User.Drawings")
		(19 "Cmts.User" user "User.Comments")
		(21 "Eco1.User" user "User.Eco1")
		(23 "Eco2.User" user "User.Eco2")
		(25 "Edge.Cuts" user "Board Geometry/Outline")
		(27 "Margin" user)
		(31 "F.CrtYd" user "Package Geometry/Place Bound Top")
		(29 "B.CrtYd" user "Package Geometry/Place Bound Bottom")
		(35 "F.Fab" user "Ref Des/Assembly Top")
		(33 "B.Fab" user "Ref Des/Assembly Bottom")
	)
	(footprint ""
		(layer "F.Cu")
		(at 476.325692 -17.506188 -90)
		(property "Reference" "R879"
			(at 0 0 270)
			(layer "F.SilkS")
			(hide yes)
			(effects
				(font
					(size 1.27 1.27)
				)
			)
		)
		(property "Value" "220R3F-1-GP"
			(at -0.0254 -2.5146 270)
			(unlocked yes)
			(layer "F.Fab")
			(hide yes)
			(effects
				(font
					(size 1.016 1.016)
					(thickness 0.1524)
				)
			)
		)
		(property "Device Type" "R603H22"
			(at -0.0254 -4.0386 270)
			(unlocked yes)
			(layer "F.Fab")
			(hide yes)
			(effects
				(font
					(size 1.016 1.016)
					(thickness 0.1524)
				)
			)
		)
		(duplicate_pad_numbers_are_jumpers no)
		(fp_line
			(start -0.4826 0)
			(end -0.2032 0)
			(stroke
				(width 0.2032)
				(type default)
			)
			(layer "F.SilkS")
		)
		(fp_line
			(start 0.2032 0)
			(end 0.4826 0)
			(stroke
				(width 0.2032)
				(type default)
			)
			(layer "F.SilkS")
		)
		(fp_rect
			(start -0.5842 1.3335)
			(end 0.5842 -1.3335)
			(stroke
				(width 0)
				(type default)
			)
			(fill no)
			(layer "F.CrtYd")
		)
		(fp_rect
			(start -0.5842 1.3335)
			(end 0.5842 -1.3335)
			(stroke
				(width 0)
				(type default)
			)
			(fill no)
			(layer "F.Fab")
		)
		(pad "1" smd custom
			(at 0 -0.762 270)
			(size 0.2159 0.2159)
			(layers "F.Cu" "F.Mask" "F.Paste")
			(net "HDD_PRSNT_35")
			(options
				(clearance outline)
				(anchor circle)
			)
			(primitives
				(gr_poly
					(pts
						(arc
							(start -0.3302 -0.4318)
							(mid -0.402042 -0.402042)
							(end -0.4318 -0.3302)
						)
						(arc
							(start -0.4318 0.3302)
							(mid -0.402042 0.402042)
							(end -0.3302 0.4318)
						)
						(arc
							(start 0.3302 0.4318)
							(mid 0.402042 0.402042)
							(end 0.4318 0.3302)
						)
						(arc
							(start 0.4318 -0.3302)
							(mid 0.402042 -0.402042)
							(end 0.3302 -0.4318)
						)
					)
					(width 0)
					(fill yes)
				)
			)
		)
		(pad "2" smd custom
			(at 0 0.762 270)
			(size 0.2159 0.2159)
			(layers "F.Cu" "F.Mask" "F.Paste")
			(net "DRIVE_B_35_INS")
			(options
				(clearance outline)
				(anchor circle)
			)
			(primitives
				(gr_poly
					(pts
						(arc
							(start -0.3302 -0.4318)
							(mid -0.402042 -0.402042)
							(end -0.4318 -0.3302)
						)
						(arc
							(start -0.4318 0.3302)
							(mid -0.402042 0.402042)
							(end -0.3302 0.4318)
						)
						(arc
							(start 0.3302 0.4318)
							(mid 0.402042 0.402042)
							(end 0.4318 0.3302)
						)
						(arc
							(start 0.4318 -0.3302)
							(mid 0.402042 -0.402042)
							(end 0.3302 -0.4318)
						)
					)
					(width 0)
					(fill yes)
				)
			)
		)
	)
	(footprint ""
		(layer "F.Cu")
		(at 26.790396 -374.64619)
		(property "Reference" "R1301"
			(at 0 0 0)
			(layer "F.SilkS")
			(hide yes)
			(effects
				(font
					(size 1.27 1.27)
				)
			)
		)
		(property "Value" "4K7R2F-GP"
			(at 0.064008 -3.993896 0)
			(unlocked yes)
			(layer "F.Fab")
			(hide yes)
			(effects
				(font
					(size 1.016 1.016)
					(thickness 0.1524)
				)
			)
		)
		(property "Device Type" "R402H16"
			(at 0.064008 -5.517896 0)
			(unlocked yes)
			(layer "F.Fab")
			(hide yes)
			(effects
				(font
					(size 1.016 1.016)
					(thickness 0.1524)
				)
			)
		)
		(duplicate_pad_numbers_are_jumpers no)
		(fp_line
			(start -0.508 -0.9398)
			(end -0.508 0.9398)
			(stroke
				(width 0.1524)
				(type default)
			)
			(layer "F.SilkS")
		)
		(fp_line
			(start 0.508 -0.9398)
			(end -0.508 -0.9398)
			(stroke
				(width 0.1524)
				(type default)
			)
			(layer "F.SilkS")
		)
		(fp_rect
			(start -0.508 0.9398)
			(end 0.508 -0.9398)
			(stroke
				(width 0)
				(type default)
			)
			(fill no)
			(layer "F.CrtYd")
		)
		(fp_rect
			(start -0.508 0.9398)
			(end 0.508 -0.9398)
			(stroke
				(width 0)
				(type default)
			)
			(fill no)
			(layer "F.Fab")
		)
		(pad "1" smd custom
			(at 0 -0.4445)
			(size 0.1397 0.1397)
			(layers "F.Cu" "F.Mask" "F.Paste")
			(net "FAN_BLUE_LED0")
			(options
				(clearance outline)
				(anchor circle)
			)
			(primitives
				(gr_poly
					(pts
						(arc
							(start -0.1778 -0.2794)
							(mid -0.249642 -0.249642)
							(end -0.2794 -0.1778)
						)
						(arc
							(start -0.2794 0.1778)
							(mid -0.249642 0.249642)
							(end -0.1778 0.2794)
						)
						(arc
							(start 0.1778 0.2794)
							(mid 0.249642 0.249642)
							(end 0.2794 0.1778)
						)
						(arc
							(start 0.2794 -0.1778)
							(mid 0.249642 -0.249642)
							(end 0.1778 -0.2794)
						)
					)
					(width 0)
					(fill yes)
				)
			)
		)
		(pad "2" smd custom
			(at 0 0.4445)
			(size 0.1397 0.1397)
			(layers "F.Cu" "F.Mask" "F.Paste")
			(net "FAN_LED0_D")
			(options
				(clearance outline)
				(anchor circle)
			)
			(primitives
				(gr_poly
					(pts
						(arc
							(start -0.1778 -0.2794)
							(mid -0.249642 -0.249642)
							(end -0.2794 -0.1778)
						)
						(arc
							(start -0.2794 0.1778)
							(mid -0.249642 0.249642)
							(end -0.1778 0.2794)
						)
						(arc
							(start 0.1778 0.2794)
							(mid 0.249642 0.249642)
							(end 0.2794 0.1778)
						)
						(arc
							(start 0.2794 -0.1778)
							(mid 0.249642 -0.249642)
							(end 0.1778 -0.2794)
						)
					)
					(width 0)
					(fill yes)
				)
			)
		)
	)
	(footprint ""
		(layer "F.Cu")
		(at 219.6084 -197.8914 -90)
		(property "Reference" "C5"
			(at 0 0 270)
			(layer "F.SilkS")
			(hide yes)
			(effects
				(font
					(size 1.27 1.27)
				)
			)
		)
		(property "Value" "SC1U16V3KX-5GP"
			(at 0 -2.8194 270)
			(unlocked yes)
			(layer "F.Fab")
			(hide yes)
			(effects
				(font
					(size 1.016 1.016)
					(thickness 0.1524)
				)
			)
		)
		(property "Device Type" "C603H36"
			(at 0 -4.3434 270)
			(unlocked yes)
			(layer "F.Fab")
			(hide yes)
			(effects
				(font
					(size 1.016 1.016)
					(thickness 0.1524)
				)
			)
		)
		(duplicate_pad_numbers_are_jumpers no)
		(fp_line
			(start 0.508 0)
			(end -0.508 0)
			(stroke
				(width 0.2032)
				(type default)
			)
			(layer "F.SilkS")
		)
		(fp_rect
			(start -0.5842 1.3335)
			(end 0.5842 -1.3335)
			(stroke
				(width 0)
				(type default)
			)
			(fill no)
			(layer "F.CrtYd")
		)
		(fp_rect
			(start -0.5842 1.3335)
			(end 0.5842 -1.3335)
			(stroke
				(width 0)
				(type default)
			)
			(fill no)
			(layer "F.Fab")
		)
		(pad "1" smd custom
			(at 0 -0.762 270)
			(size 0.2159 0.2159)
			(layers "F.Cu" "F.Mask" "F.Paste")
			(net "P3V3_STBY_B")
			(options
				(clearance outline)
				(anchor circle)
			)
			(primitives
				(gr_poly
					(pts
						(arc
							(start -0.3302 -0.4318)
							(mid -0.402042 -0.402042)
							(end -0.4318 -0.3302)
						)
						(arc
							(start -0.4318 0.3302)
							(mid -0.402042 0.402042)
							(end -0.3302 0.4318)
						)
						(arc
							(start 0.3302 0.4318)
							(mid 0.402042 0.402042)
							(end 0.4318 0.3302)
						)
						(arc
							(start 0.4318 -0.3302)
							(mid 0.402042 -0.402042)
							(end 0.3302 -0.4318)
						)
					)
					(width 0)
					(fill yes)
				)
			)
		)
		(pad "2" smd custom
			(at 0 0.762 270)
			(size 0.2159 0.2159)
			(layers "F.Cu" "F.Mask" "F.Paste")
			(net "GND")
			(options
				(clearance outline)
				(anchor circle)
			)
			(primitives
				(gr_poly
					(pts
						(arc
							(start -0.3302 -0.4318)
							(mid -0.402042 -0.402042)
							(end -0.4318 -0.3302)
						)
						(arc
							(start -0.4318 0.3302)
							(mid -0.402042 0.402042)
							(end -0.3302 0.4318)
						)
						(arc
							(start 0.3302 0.4318)
							(mid 0.402042 0.402042)
							(end 0.4318 0.3302)
						)
						(arc
							(start 0.4318 -0.3302)
							(mid 0.402042 -0.402042)
							(end 0.3302 -0.4318)
						)
					)
					(width 0)
					(fill yes)
				)
			)
		)
	)
	(footprint ""
		(layer "F.Cu")
		(at 148.5392 -246.253 -90)
		(property "Reference" "R230"
			(at 0 0 270)
			(layer "F.SilkS")
			(hide yes)
			(effects
				(font
					(size 1.27 1.27)
				)
			)
		)
		(property "Value" "0R2J-2-GP"
			(at 0.064008 -3.993896 270)
			(unlocked yes)
			(layer "F.Fab")
			(hide yes)
			(effects
				(font
					(size 1.016 1.016)
					(thickness 0.1524)
				)
			)
		)
		(property "Device Type" "R402H16"
			(at 0.064008 -5.517896 270)
			(unlocked yes)
			(layer "F.Fab")
			(hide yes)
			(effects
				(font
					(size 1.016 1.016)
					(thickness 0.1524)
				)
			)
		)
		(duplicate_pad_numbers_are_jumpers no)
		(fp_line
			(start -0.508 -0.9398)
			(end -0.508 0.9398)
			(stroke
				(width 0.1524)
				(type default)
			)
			(layer "F.SilkS")
		)
		(fp_line
			(start 0.508 -0.9398)
			(end -0.508 -0.9398)
			(stroke
				(width 0.1524)
				(type default)
			)
			(layer "F.SilkS")
		)
		(fp_rect
			(start -0.508 0.9398)
			(end 0.508 -0.9398)
			(stroke
				(width 0)
				(type default)
			)
			(fill no)
			(layer "F.CrtYd")
		)
		(fp_rect
			(start -0.508 0.9398)
			(end 0.508 -0.9398)
			(stroke
				(width 0)
				(type default)
			)
			(fill no)
			(layer "F.Fab")
		)
		(pad "1" smd custom
			(at 0 -0.4445 270)
			(size 0.1397 0.1397)
			(layers "F.Cu" "F.Mask" "F.Paste")
			(net "DRIVE_B_4_PWR")
			(options
				(clearance outline)
				(anchor circle)
			)
			(primitives
				(gr_poly
					(pts
						(arc
							(start -0.1778 -0.2794)
							(mid -0.249642 -0.249642)
							(end -0.2794 -0.1778)
						)
						(arc
							(start -0.2794 0.1778)
							(mid -0.249642 0.249642)
							(end -0.1778 0.2794)
						)
						(arc
							(start 0.1778 0.2794)
							(mid 0.249642 0.249642)
							(end 0.2794 0.1778)
						)
						(arc
							(start 0.2794 -0.1778)
							(mid 0.249642 -0.249642)
							(end 0.1778 -0.2794)
						)
					)
					(width 0)
					(fill yes)
				)
			)
		)
		(pad "2" smd custom
			(at 0 0.4445 270)
			(size 0.1397 0.1397)
			(layers "F.Cu" "F.Mask" "F.Paste")
			(net "SW_PWR_R_HDD4")
			(options
				(clearance outline)
				(anchor circle)
			)
			(primitives
				(gr_poly
					(pts
						(arc
							(start -0.1778 -0.2794)
							(mid -0.249642 -0.249642)
							(end -0.2794 -0.1778)
						)
						(arc
							(start -0.2794 0.1778)
							(mid -0.249642 0.249642)
							(end -0.1778 0.2794)
						)
						(arc
							(start 0.1778 0.2794)
							(mid 0.249642 0.249642)
							(end 0.2794 0.1778)
						)
						(arc
							(start 0.2794 -0.1778)
							(mid 0.249642 -0.249642)
							(end 0.1778 -0.2794)
						)
					)
					(width 0)
					(fill yes)
				)
			)
		)
	)
	(footprint ""
		(layer "F.Cu")
		(at 242.57 -138.7094 180)
		(property "Reference" "R605"
			(at 0 0 180)
			(layer "F.SilkS")
			(hide yes)
			(effects
				(font
					(size 1.27 1.27)
				)
			)
		)
		(property "Value" "2K2R2F-GP"
			(at 0.064008 -3.993896 180)
			(unlocked yes)
			(layer "F.Fab")
			(hide yes)
			(effects
				(font
					(size 1.016 1.016)
					(thickness 0.1524)
				)
			)
		)
		(property "Device Type" "R402H16"
			(at 0.064008 -5.517896 180)
			(unlocked yes)
			(layer "F.Fab")
			(hide yes)
			(effects
				(font
					(size 1.016 1.016)
					(thickness 0.1524)
				)
			)
		)
		(duplicate_pad_numbers_are_jumpers no)
		(fp_line
			(start 0.508 -0.9398)
			(end -0.508 -0.9398)
			(stroke
				(width 0.1524)
				(type default)
			)
			(layer "F.SilkS")
		)
		(fp_line
			(start -0.508 -0.9398)
			(end -0.508 0.9398)
			(stroke
				(width 0.1524)
				(type default)
			)
			(layer "F.SilkS")
		)
		(fp_rect
			(start -0.508 0.9398)
			(end 0.508 -0.9398)
			(stroke
				(width 0)
				(type default)
			)
			(fill no)
			(layer "F.CrtYd")
		)
		(fp_rect
			(start -0.508 0.9398)
			(end 0.508 -0.9398)
			(stroke
				(width 0)
				(type default)
			)
			(fill no)
			(layer "F.Fab")
		)
		(pad "1" smd custom
			(at 0 -0.4445 180)
			(size 0.1397 0.1397)
			(layers "F.Cu" "F.Mask" "F.Paste")
			(net "P3V3_STBY_B")
			(options
				(clearance outline)
				(anchor circle)
			)
			(primitives
				(gr_poly
					(pts
						(arc
							(start -0.1778 -0.2794)
							(mid -0.249642 -0.249642)
							(end -0.2794 -0.1778)
						)
						(arc
							(start -0.2794 0.1778)
							(mid -0.249642 0.249642)
							(end -0.1778 0.2794)
						)
						(arc
							(start 0.1778 0.2794)
							(mid 0.249642 0.249642)
							(end 0.2794 0.1778)
						)
						(arc
							(start 0.2794 -0.1778)
							(mid 0.249642 -0.249642)
							(end 0.1778 -0.2794)
						)
					)
					(width 0)
					(fill yes)
				)
			)
		)
		(pad "2" smd custom
			(at 0 0.4445 180)
			(size 0.1397 0.1397)
			(layers "F.Cu" "F.Mask" "F.Paste")
			(net "I2C_SCC_B_SCL")
			(options
				(clearance outline)
				(anchor circle)
			)
			(primitives
				(gr_poly
					(pts
						(arc
							(start -0.1778 -0.2794)
							(mid -0.249642 -0.249642)
							(end -0.2794 -0.1778)
						)
						(arc
							(start -0.2794 0.1778)
							(mid -0.249642 0.249642)
							(end -0.1778 0.2794)
						)
						(arc
							(start 0.1778 0.2794)
							(mid 0.249642 0.249642)
							(end 0.2794 0.1778)
						)
						(arc
							(start 0.2794 -0.1778)
							(mid 0.249642 -0.249642)
							(end 0.1778 -0.2794)
						)
					)
					(width 0)
					(fill yes)
				)
			)
		)
	)
	(footprint ""
		(layer "F.Cu")
		(at 401.828 -142.875 -90)
		(property "Reference" "R545"
			(at 0 0 270)
			(layer "F.SilkS")
			(hide yes)
			(effects
				(font
					(size 1.27 1.27)
				)
			)
		)
		(property "Value" "300KR2F-GP"
			(at 0.064008 -3.993896 270)
			(unlocked yes)
			(layer "F.Fab")
			(hide yes)
			(effects
				(font
					(size 1.016 1.016)
					(thickness 0.1524)
				)
			)
		)
		(property "Device Type" "R402H16"
			(at 0.064008 -5.517896 270)
			(unlocked yes)
			(layer "F.Fab")
			(hide yes)
			(effects
				(font
					(size 1.016 1.016)
					(thickness 0.1524)
				)
			)
		)
		(duplicate_pad_numbers_are_jumpers no)
		(fp_line
			(start -0.508 -0.9398)
			(end -0.508 0.9398)
			(stroke
				(width 0.1524)
				(type default)
			)
			(layer "F.SilkS")
		)
		(fp_line
			(start 0.508 -0.9398)
			(end -0.508 -0.9398)
			(stroke
				(width 0.1524)
				(type default)
			)
			(layer "F.SilkS")
		)
		(fp_rect
			(start -0.508 0.9398)
			(end 0.508 -0.9398)
			(stroke
				(width 0)
				(type default)
			)
			(fill no)
			(layer "F.CrtYd")
		)
		(fp_rect
			(start -0.508 0.9398)
			(end 0.508 -0.9398)
			(stroke
				(width 0)
				(type default)
			)
			(fill no)
			(layer "F.Fab")
		)
		(pad "1" smd custom
			(at 0 -0.4445 270)
			(size 0.1397 0.1397)
			(layers "F.Cu" "F.Mask" "F.Paste")
			(net "SW_HDD_N20")
			(options
				(clearance outline)
				(anchor circle)
			)
			(primitives
				(gr_poly
					(pts
						(arc
							(start -0.1778 -0.2794)
							(mid -0.249642 -0.249642)
							(end -0.2794 -0.1778)
						)
						(arc
							(start -0.2794 0.1778)
							(mid -0.249642 0.249642)
							(end -0.1778 0.2794)
						)
						(arc
							(start 0.1778 0.2794)
							(mid 0.249642 0.249642)
							(end 0.2794 0.1778)
						)
						(arc
							(start 0.2794 -0.1778)
							(mid 0.249642 -0.249642)
							(end 0.1778 -0.2794)
						)
					)
					(width 0)
					(fill yes)
				)
			)
		)
		(pad "2" smd custom
			(at 0 0.4445 270)
			(size 0.1397 0.1397)
			(layers "F.Cu" "F.Mask" "F.Paste")
			(net "P12V_B")
			(options
				(clearance outline)
				(anchor circle)
			)
			(primitives
				(gr_poly
					(pts
						(arc
							(start -0.1778 -0.2794)
							(mid -0.249642 -0.249642)
							(end -0.2794 -0.1778)
						)
						(arc
							(start -0.2794 0.1778)
							(mid -0.249642 0.249642)
							(end -0.1778 0.2794)
						)
						(arc
							(start 0.1778 0.2794)
							(mid 0.249642 0.249642)
							(end 0.2794 0.1778)
						)
						(arc
							(start 0.2794 -0.1778)
							(mid 0.249642 -0.249642)
							(end 0.1778 -0.2794)
						)
					)
					(width 0)
					(fill yes)
				)
			)
		)
	)
	(footprint ""
		(layer "F.Cu")
		(at 305.044348 -357.530908 180)
		(property "Reference" "C631"
			(at 0 0 180)
			(layer "F.SilkS")
			(hide yes)
			(effects
				(font
					(size 1.27 1.27)
				)
			)
		)
		(property "Value" "SCD1U16V2KX-3GP"
			(at 1.1811 -2.7051 180)
			(unlocked yes)
			(layer "F.Fab")
			(hide yes)
			(effects
				(font
					(size 1.016 1.016)
					(thickness 0.1524)
				)
			)
		)
		(property "Device Type" "C402H22"
			(at 1.1811 -4.2291 180)
			(unlocked yes)
			(layer "F.Fab")
			(hide yes)
			(effects
				(font
					(size 1.016 1.016)
					(thickness 0.1524)
				)
			)
		)
		(duplicate_pad_numbers_are_jumpers no)
		(fp_rect
			(start -0.4318 0.9525)
			(end 0.4318 -0.9525)
			(stroke
				(width 0)
				(type default)
			)
			(fill no)
			(layer "F.CrtYd")
		)
		(fp_rect
			(start -0.4318 0.9525)
			(end 0.4318 -0.9525)
			(stroke
				(width 0)
				(type default)
			)
			(fill no)
			(layer "F.Fab")
		)
		(pad "1" smd custom
			(at 0 -0.4445 180)
			(size 0.1524 0.1524)
			(layers "F.Cu" "F.Mask" "F.Paste")
			(net "P3V3_IN")
			(options
				(clearance outline)
				(anchor circle)
			)
			(primitives
				(gr_poly
					(pts
						(arc
							(start 0.3048 -0.2032)
							(mid 0.275042 -0.275042)
							(end 0.2032 -0.3048)
						)
						(arc
							(start -0.2032 -0.3048)
							(mid -0.275042 -0.275042)
							(end -0.3048 -0.2032)
						)
						(arc
							(start -0.3048 0.2032)
							(mid -0.275042 0.275042)
							(end -0.2032 0.3048)
						)
						(arc
							(start 0.2032 0.3048)
							(mid 0.275042 0.275042)
							(end 0.3048 0.2032)
						)
					)
					(width 0)
					(fill yes)
				)
			)
		)
		(pad "2" smd custom
			(at 0 0.4445 180)
			(size 0.1524 0.1524)
			(layers "F.Cu" "F.Mask" "F.Paste")
			(net "GND")
			(options
				(clearance outline)
				(anchor circle)
			)
			(primitives
				(gr_poly
					(pts
						(arc
							(start 0.3048 -0.2032)
							(mid 0.275042 -0.275042)
							(end 0.2032 -0.3048)
						)
						(arc
							(start -0.2032 -0.3048)
							(mid -0.275042 -0.275042)
							(end -0.3048 -0.2032)
						)
						(arc
							(start -0.3048 0.2032)
							(mid -0.275042 0.275042)
							(end -0.2032 0.3048)
						)
						(arc
							(start 0.2032 0.3048)
							(mid 0.275042 0.275042)
							(end 0.3048 0.2032)
						)
					)
					(width 0)
					(fill yes)
				)
			)
		)
	)
)
